# BASEBOARD_FAB2 (Tioga Pass) — schematic netlist excerpt (pin names and nets, part order shuffled) for the footprints in the layout excerpt that follows; sources: Cadence DE-HDL packaged netlist, KiCad conversion of Wiwynn_Tioga_Pass_MB.brd

C4B7  CAP  2200PF 50V 10% X7R  pkg 0402LF  page 234 : A = VR_COMP_PVPP_KLM ; B = VR_FB_PVPP_KLM
R7B15  RES  20.0K 1% CHIP  pkg 0402  page 232 : A = VSENSE_PVPP_DEF ; B = VR_FB_PVPP_DEF

U6F1  PCA9617  IC  pkg SSOP  page 99
  VCCA  = PVCCIO_CPU0
  SCLA  = SMB_DDR_ABC_SCL_G
  SDAA  = SMB_DDR_ABC_SDA_G
  EN  = TP_SMB_DDR_ABC_EN
  SDAB  = SMB_DDR_ABC_VPP_SDA_R
  SCLB  = SMB_DDR_ABC_VPP_SCL_R
  VCCB  = PVPP_ABC

(kicad_pcb
	(version 20260206)
	(generator "pcbnew")
	(generator_version "10.0")
	(general
		(thickness 1.6)
		(legacy_teardrops no)
	)
	(paper "A4")
	(title_block
		(title "Wiwynn_Tioga_Pass_MB.brd")
		(comment 1 "Tioga Pass / footprints 2075-2077 of 4770")
	)
	(layers
		(0 "F.Cu" signal "TOP")
		(4 "In1.Cu" signal "L2GND")
		(6 "In2.Cu" signal "L3")
		(8 "In3.Cu" signal "L4GND")
		(10 "In4.Cu" signal "L5")
		(12 "In5.Cu" signal "L6GND")
		(14 "In6.Cu" signal "L7VCC")
		(16 "In7.Cu" signal "L8VCC")
		(18 "In8.Cu" signal "L9GND")
		(20 "In9.Cu" signal "L10")
		(22 "In10.Cu" signal "L11GND")
		(24 "In11.Cu" signal "L12")
		(26 "In12.Cu" signal "L13GND")
		(2 "B.Cu" signal "BOTTOM")
		(9 "F.Adhes" user "F.Adhesive")
		(11 "B.Adhes" user "B.Adhesive")
		(13 "F.Paste" user "Package Geometry/Pastemask Top")
		(15 "B.Paste" user "Package Geometry/Pastemask Bottom")
		(5 "F.SilkS" user "Ref Des/Silkscreen Top")
		(7 "B.SilkS" user "Ref Des/Silkscreen Bottom")
		(1 "F.Mask" user "Board Geometry/Soldermask Top")
		(3 "B.Mask" user "Board Geometry/Soldermask Bottom")
		(17 "Dwgs.User" user "User.Drawings")
		(19 "Cmts.User" user "User.Comments")
		(21 "Eco1.User" user "User.Eco1")
		(23 "Eco2.User" user "User.Eco2")
		(25 "Edge.Cuts" user "Board Geometry/Outline")
		(27 "Margin" user)
		(31 "F.CrtYd" user "Package Geometry/Place Bound Top")
		(29 "B.CrtYd" user "Package Geometry/Place Bound Bottom")
		(35 "F.Fab" user "Ref Des/Assembly Top")
		(33 "B.Fab" user "Ref Des/Assembly Bottom")
	)
	(footprint ""
		(layer "F.Cu")
		(at 337.0326 -128.2065 180)
		(property "Reference" "R7B15"
			(at 0 0 180)
			(layer "F.SilkS")
			(hide yes)
			(effects
				(font
					(size 1.27 1.27)
				)
			)
		)
		(property "Value" ""
			(at 0 0 180)
			(layer "F.Fab")
			(effects
				(font
					(size 1.27 1.27)
				)
			)
		)
		(duplicate_pad_numbers_are_jumpers no)
		(fp_poly
			(pts
				(xy -0.2794 -0.1016) (xy 0.2794 -0.1016) (xy 0.2794 0.9906) (xy -0.2794 0.9906)
			)
			(stroke
				(width 0)
				(type default)
			)
			(fill no)
			(layer "F.CrtYd")
		)
		(fp_line
			(start 0.2794 0.9906)
			(end 0.2794 -0.1016)
			(stroke
				(width 0.1)
				(type default)
			)
			(layer "F.Fab")
		)
		(fp_line
			(start 0.2794 -0.1016)
			(end -0.2794 -0.1016)
			(stroke
				(width 0.1)
				(type default)
			)
			(layer "F.Fab")
		)
		(fp_line
			(start -0.2794 0.9906)
			(end 0.2794 0.9906)
			(stroke
				(width 0.1)
				(type default)
			)
			(layer "F.Fab")
		)
		(fp_line
			(start -0.2794 -0.1016)
			(end -0.2794 0.9906)
			(stroke
				(width 0.1)
				(type default)
			)
			(layer "F.Fab")
		)
		(pad "1" smd rect
			(at 0 0 180)
			(size 0.508 0.508)
			(layers "F.Cu" "F.Mask" "F.Paste")
			(net "VSENSE_PVPP_DEF")
		)
		(pad "2" smd rect
			(at 0 0.889 180)
			(size 0.508 0.508)
			(layers "F.Cu" "F.Mask" "F.Paste")
			(net "VR_FB_PVPP_DEF")
		)
		(zone
			(layer "F.Cu")
			(hatch none 0.5)
			(connect_pads
				(clearance 0)
			)
			(min_thickness 0.25)
			(keepout
				(tracks not_allowed)
				(vias allowed)
				(pads allowed)
				(copperpour not_allowed)
				(footprints allowed)
			)
			(placement
				(enabled no)
				(sheetname "")
			)
			(fill
				(thermal_gap 0.5)
				(thermal_bridge_width 0.5)
				(island_removal_mode 0)
			)
			(polygon
				(pts
					(xy 337.2866 -128.8415) (xy 336.7786 -128.8415) (xy 336.7786 -128.4605) (xy 337.2866 -128.4605)
				)
			)
		)
		(zone
			(layer "F.Cu")
			(hatch none 0.5)
			(connect_pads
				(clearance 0)
			)
			(min_thickness 0.25)
			(keepout
				(tracks allowed)
				(vias not_allowed)
				(pads allowed)
				(copperpour not_allowed)
				(footprints allowed)
			)
			(placement
				(enabled no)
				(sheetname "")
			)
			(fill
				(thermal_gap 0.5)
				(thermal_bridge_width 0.5)
				(island_removal_mode 0)
			)
			(polygon
				(pts
					(xy 337.2866 -128.4605) (xy 336.7786 -128.4605) (xy 336.7786 -128.8415) (xy 337.2866 -128.8415)
				)
			)
		)
	)
	(footprint ""
		(layer "F.Cu")
		(at 171.577 -131.0005 180)
		(property "Reference" "C4B7"
			(at 0 0 180)
			(layer "F.SilkS")
			(hide yes)
			(effects
				(font
					(size 1.27 1.27)
				)
			)
		)
		(property "Value" ""
			(at 0 0 180)
			(layer "F.Fab")
			(effects
				(font
					(size 1.27 1.27)
				)
			)
		)
		(duplicate_pad_numbers_are_jumpers no)
		(fp_poly
			(pts
				(xy 0.3048 -0.1016) (xy 0.3048 0.9906) (xy -0.3048 0.9906) (xy -0.3048 -0.1016)
			)
			(stroke
				(width 0)
				(type default)
			)
			(fill no)
			(layer "F.CrtYd")
		)
		(fp_line
			(start 0.3048 0.9906)
			(end 0.3048 -0.1016)
			(stroke
				(width 0.1)
				(type default)
			)
			(layer "F.Fab")
		)
		(fp_line
			(start 0.3048 -0.1016)
			(end -0.3048 -0.1016)
			(stroke
				(width 0.1)
				(type default)
			)
			(layer "F.Fab")
		)
		(fp_line
			(start -0.3048 0.9906)
			(end 0.3048 0.9906)
			(stroke
				(width 0.1)
				(type default)
			)
			(layer "F.Fab")
		)
		(fp_line
			(start -0.3048 -0.1016)
			(end -0.3048 0.9906)
			(stroke
				(width 0.1)
				(type default)
			)
			(layer "F.Fab")
		)
		(pad "1" smd rect
			(at 0 0 180)
			(size 0.508 0.508)
			(layers "F.Cu" "F.Mask" "F.Paste")
			(net "VR_COMP_PVPP_KLM")
		)
		(pad "2" smd rect
			(at 0 0.889 180)
			(size 0.508 0.508)
			(layers "F.Cu" "F.Mask" "F.Paste")
			(net "VR_FB_PVPP_KLM")
		)
		(zone
			(layer "F.Cu")
			(hatch none 0.5)
			(connect_pads
				(clearance 0)
			)
			(min_thickness 0.25)
			(keepout
				(tracks not_allowed)
				(vias allowed)
				(pads allowed)
				(copperpour not_allowed)
				(footprints allowed)
			)
			(placement
				(enabled no)
				(sheetname "")
			)
			(fill
				(thermal_gap 0.5)
				(thermal_bridge_width 0.5)
				(island_removal_mode 0)
			)
			(polygon
				(pts
					(xy 171.831 -131.6355) (xy 171.323 -131.6355) (xy 171.323 -131.2545) (xy 171.831 -131.2545)
				)
			)
		)
		(zone
			(layer "F.Cu")
			(hatch none 0.5)
			(connect_pads
				(clearance 0)
			)
			(min_thickness 0.25)
			(keepout
				(tracks allowed)
				(vias not_allowed)
				(pads allowed)
				(copperpour not_allowed)
				(footprints allowed)
			)
			(placement
				(enabled no)
				(sheetname "")
			)
			(fill
				(thermal_gap 0.5)
				(thermal_bridge_width 0.5)
				(island_removal_mode 0)
			)
			(polygon
				(pts
					(xy 171.831 -131.2545) (xy 171.323 -131.2545) (xy 171.323 -131.6355) (xy 171.831 -131.6355)
				)
			)
		)
	)
	(footprint ""
		(layer "F.Cu")
		(at 323.6087 -32.42818 -90)
		(property "Reference" "U6F1"
			(at 1.94818 3.61823 90)
			(unlocked yes)
			(layer "F.SilkS")
			(effects
				(font
					(size 0.7874 0.5842)
					(thickness 0.1524)
				)
			)
		)
		(property "Value" ""
			(at 0 0 270)
			(layer "F.Fab")
			(effects
				(font
					(size 1.27 1.27)
				)
			)
		)
		(duplicate_pad_numbers_are_jumpers no)
		(fp_line
			(start 3.225038 2.52476)
			(end 1.348486 2.52476)
			(stroke
				(width 0.1524)
				(type default)
			)
			(layer "F.SilkS")
		)
		(fp_line
			(start 3.225292 -0.57404)
			(end 1.352804 -0.57404)
			(stroke
				(width 0.1524)
				(type default)
			)
			(layer "F.SilkS")
		)
		(fp_circle
			(center -0.946404 -0.683514)
			(end -0.946404 -0.810514)
			(stroke
				(width 0.254)
				(type default)
			)
			(fill no)
			(layer "F.SilkS")
		)
		(fp_poly
			(pts
				(xy 0.7366 -0.57404) (xy 3.8354 -0.57404) (xy 3.8354 2.52476) (xy 0.7366 2.52476)
			)
			(stroke
				(width 0)
				(type default)
			)
			(fill no)
			(layer "F.CrtYd")
		)
		(fp_line
			(start 0.7366 2.52476)
			(end 0.7366 -0.57404)
			(stroke
				(width 0.1)
				(type default)
			)
			(layer "F.Fab")
		)
		(fp_line
			(start 3.8354 2.52476)
			(end 0.7366 2.52476)
			(stroke
				(width 0.1)
				(type default)
			)
			(layer "F.Fab")
		)
		(fp_line
			(start 0.7366 -0.57404)
			(end 3.8354 -0.57404)
			(stroke
				(width 0.1)
				(type default)
			)
			(layer "F.Fab")
		)
		(fp_line
			(start 3.8354 -0.57404)
			(end 3.8354 2.52476)
			(stroke
				(width 0.1)
				(type default)
			)
			(layer "F.Fab")
		)
		(fp_circle
			(center -1.454404 -0.556514)
			(end -1.454404 -0.683514)
			(stroke
				(width 0.254)
				(type default)
			)
			(fill no)
			(layer "F.Fab")
		)
		(pad "1" smd rect
			(at 0 0 270)
			(size 1.778 0.4572)
			(layers "F.Cu" "F.Mask" "F.Paste")
			(net "PVCCIO_CPU0")
		)
		(pad "2" smd rect
			(at 0 0.65024 270)
			(size 1.778 0.4572)
			(layers "F.Cu" "F.Mask" "F.Paste")
			(net "SMB_DDR_ABC_SCL_G")
		)
		(pad "3" smd rect
			(at 0 1.30048 270)
			(size 1.778 0.4572)
			(layers "F.Cu" "F.Mask" "F.Paste")
			(net "SMB_DDR_ABC_SDA_G")
		)
		(pad "4" smd rect
			(at 0 1.95072 270)
			(size 1.778 0.4572)
			(layers "F.Cu" "F.Mask" "F.Paste")
			(net "GND")
		)
		(pad "5" smd rect
			(at 4.572 1.95072 270)
			(size 1.778 0.4572)
			(layers "F.Cu" "F.Mask" "F.Paste")
			(net "TP_SMB_DDR_ABC_EN")
		)
		(pad "6" smd rect
			(at 4.572 1.30048 270)
			(size 1.778 0.4572)
			(layers "F.Cu" "F.Mask" "F.Paste")
			(net "SMB_DDR_ABC_VPP_SDA_R")
		)
		(pad "7" smd rect
			(at 4.572 0.65024 270)
			(size 1.778 0.4572)
			(layers "F.Cu" "F.Mask" "F.Paste")
			(net "SMB_DDR_ABC_VPP_SCL_R")
		)
		(pad "8" smd rect
			(at 4.572 0 270)
			(size 1.778 0.4572)
			(layers "F.Cu" "F.Mask" "F.Paste")
			(net "PVPP_ABC")
		)
	)
)
